# T6G (Grand Teton) — schematic netlist excerpt (pin names and nets, part order shuffled) for the footprints in the layout excerpt that follows; sources: Cadence DE-HDL packaged netlist, KiCad conversion of 04192023_DAF0TMB3IC0_F0TG_MB_C_brd_V02_OCP.brd

R8030  Q_RES  0 5% CHIP  pkg 0402LF  page 152 : A = P12V_SCM_FAULT_N ; B = P12V_SCM_FAULT_R_N
R153  Q_RES  0 5% CHIP  pkg 0402LF  page 144 : A = M2_SSD0_CLKREQ_EN_N ; B = M2_SSD0_CLKREQ_EN_N_BUF
R614  Q_RES  0 5% CHIP  pkg 0201LF  page 298 : A = CLK_100M_RETIMER_CPU0_P2_R_DN ; B = CLK_100M_RETIMER_CPU0_P2_DN

(kicad_pcb
	(version 20260206)
	(generator "pcbnew")
	(generator_version "10.0")
	(general
		(thickness 1.6)
		(legacy_teardrops no)
	)
	(paper "A4")
	(title_block
		(title "04192023_DAF0TMB3IC0_F0TG_MB_C_brd_V02_OCP.brd")
		(comment 1 "Grand Teton / footprints 4133-4135 of 8354")
	)
	(layers
		(0 "F.Cu" signal "TOP")
		(4 "In1.Cu" signal "GND")
		(6 "In2.Cu" signal "IN1")
		(8 "In3.Cu" signal "GND1")
		(10 "In4.Cu" signal "IN2")
		(12 "In5.Cu" signal "GND2")
		(14 "In6.Cu" signal "IN3")
		(16 "In7.Cu" signal "GND3")
		(18 "In8.Cu" signal "VCC")
		(20 "In9.Cu" signal "VCC1")
		(22 "In10.Cu" signal "GND4")
		(24 "In11.Cu" signal "IN4")
		(26 "In12.Cu" signal "GND5")
		(28 "In13.Cu" signal "IN5")
		(30 "In14.Cu" signal "GND6")
		(32 "In15.Cu" signal "IN6")
		(34 "In16.Cu" signal "GND7")
		(2 "B.Cu" signal "BOTTOM")
		(9 "F.Adhes" user "F.Adhesive")
		(11 "B.Adhes" user "B.Adhesive")
		(13 "F.Paste" user "Package Geometry/Pastemask Top")
		(15 "B.Paste" user "Package Geometry/Pastemask Bottom")
		(5 "F.SilkS" user "Ref Des/Silkscreen Top")
		(7 "B.SilkS" user "Ref Des/Silkscreen Bottom")
		(1 "F.Mask" user "Board Geometry/Soldermask Top")
		(3 "B.Mask" user "Board Geometry/Soldermask Bottom")
		(17 "Dwgs.User" user "User.Drawings")
		(19 "Cmts.User" user "User.Comments")
		(21 "Eco1.User" user "User.Eco1")
		(23 "Eco2.User" user "User.Eco2")
		(25 "Edge.Cuts" user "Board Geometry/Outline")
		(27 "Margin" user)
		(31 "F.CrtYd" user "Package Geometry/Place Bound Top")
		(29 "B.CrtYd" user "Package Geometry/Place Bound Bottom")
		(35 "F.Fab" user "Ref Des/Assembly Top")
		(33 "B.Fab" user "Ref Des/Assembly Bottom")
	)
	(footprint ""
		(layer "F.Cu")
		(at 398.155668 -395.333474)
		(property "Reference" "R614"
			(at 0 0 0)
			(layer "F.SilkS")
			(hide yes)
			(effects
				(font
					(size 1.27 1.27)
				)
			)
		)
		(property "Value" ""
			(at 0 0 0)
			(layer "F.Fab")
			(effects
				(font
					(size 1.27 1.27)
				)
			)
		)
		(duplicate_pad_numbers_are_jumpers no)
		(fp_line
			(start -0.32512 -0.175006)
			(end 0.32512 -0.175006)
			(stroke
				(width 0.1)
				(type default)
			)
			(layer "F.Fab")
		)
		(fp_line
			(start -0.32512 0.175006)
			(end -0.32512 -0.175006)
			(stroke
				(width 0.1)
				(type default)
			)
			(layer "F.Fab")
		)
		(fp_line
			(start 0.32512 -0.175006)
			(end 0.32512 0.175006)
			(stroke
				(width 0.1)
				(type default)
			)
			(layer "F.Fab")
		)
		(fp_line
			(start 0.32512 0.175006)
			(end -0.32512 0.175006)
			(stroke
				(width 0.1)
				(type default)
			)
			(layer "F.Fab")
		)
		(pad "1" smd rect
			(at -0.2667 0)
			(size 0.3048 0.381)
			(layers "F.Cu" "F.Mask" "F.Paste")
			(net "CLK_100M_RETIMER_CPU0_P2_R_DN")
		)
		(pad "2" smd rect
			(at 0.2667 0 180)
			(size 0.3048 0.381)
			(layers "F.Cu" "F.Mask" "F.Paste")
			(net "CLK_100M_RETIMER_CPU0_P2_DN")
		)
	)
	(footprint ""
		(layer "F.Cu")
		(at 164.544756 -43.193462)
		(property "Reference" "R153"
			(at 0 0 0)
			(layer "F.SilkS")
			(hide yes)
			(effects
				(font
					(size 1.27 1.27)
				)
			)
		)
		(property "Value" ""
			(at 0 0 0)
			(layer "F.Fab")
			(effects
				(font
					(size 1.27 1.27)
				)
			)
		)
		(duplicate_pad_numbers_are_jumpers no)
		(fp_line
			(start -0.7874 -0.4064)
			(end 0.7874 -0.4064)
			(stroke
				(width 0.1524)
				(type default)
			)
			(layer "F.SilkS")
		)
		(fp_line
			(start -0.7874 0.4064)
			(end -0.7874 -0.4064)
			(stroke
				(width 0.1524)
				(type default)
			)
			(layer "F.SilkS")
		)
		(fp_line
			(start 0.7874 -0.4064)
			(end 0.7874 0.4064)
			(stroke
				(width 0.1524)
				(type default)
			)
			(layer "F.SilkS")
		)
		(fp_line
			(start 0.7874 0.4064)
			(end -0.7874 0.4064)
			(stroke
				(width 0.1524)
				(type default)
			)
			(layer "F.SilkS")
		)
		(fp_line
			(start -0.67945 -0.305054)
			(end -0.12065 -0.305054)
			(stroke
				(width 0.1)
				(type default)
			)
			(layer "F.Fab")
		)
		(fp_line
			(start -0.67945 0.3048)
			(end -0.67945 -0.305054)
			(stroke
				(width 0.1)
				(type default)
			)
			(layer "F.Fab")
		)
		(fp_line
			(start -0.12065 -0.305054)
			(end -0.12065 -0.2794)
			(stroke
				(width 0.1)
				(type default)
			)
			(layer "F.Fab")
		)
		(fp_line
			(start -0.12065 -0.2794)
			(end 0.12065 -0.2794)
			(stroke
				(width 0.1)
				(type default)
			)
			(layer "F.Fab")
		)
		(fp_line
			(start -0.12065 0.2794)
			(end -0.12065 0.3048)
			(stroke
				(width 0.1)
				(type default)
			)
			(layer "F.Fab")
		)
		(fp_line
			(start -0.12065 0.3048)
			(end -0.67945 0.3048)
			(stroke
				(width 0.1)
				(type default)
			)
			(layer "F.Fab")
		)
		(fp_line
			(start 0.120396 0.2794)
			(end -0.12065 0.2794)
			(stroke
				(width 0.1)
				(type default)
			)
			(layer "F.Fab")
		)
		(fp_line
			(start 0.120396 0.3048)
			(end 0.120396 0.2794)
			(stroke
				(width 0.1)
				(type default)
			)
			(layer "F.Fab")
		)
		(fp_line
			(start 0.12065 -0.3048)
			(end 0.67945 -0.3048)
			(stroke
				(width 0.1)
				(type default)
			)
			(layer "F.Fab")
		)
		(fp_line
			(start 0.12065 -0.2794)
			(end 0.12065 -0.3048)
			(stroke
				(width 0.1)
				(type default)
			)
			(layer "F.Fab")
		)
		(fp_line
			(start 0.67945 -0.3048)
			(end 0.67945 0.3048)
			(stroke
				(width 0.1)
				(type default)
			)
			(layer "F.Fab")
		)
		(fp_line
			(start 0.67945 0.3048)
			(end 0.120396 0.3048)
			(stroke
				(width 0.1)
				(type default)
			)
			(layer "F.Fab")
		)
		(pad "1" smd circle
			(at -0.40005 0)
			(size 0 0)
			(layers "F.Cu" "F.Mask" "F.Paste")
			(net "M2_SSD0_CLKREQ_EN_N")
		)
		(pad "2" smd circle
			(at 0.40005 0)
			(size 0 0)
			(layers "F.Cu" "F.Mask" "F.Paste")
			(net "M2_SSD0_CLKREQ_EN_N_BUF")
		)
	)
	(footprint ""
		(layer "F.Cu")
		(at 193.167 -28.194 -90)
		(property "Reference" "R8030"
			(at 0 0 270)
			(layer "F.SilkS")
			(hide yes)
			(effects
				(font
					(size 1.27 1.27)
				)
			)
		)
		(property "Value" ""
			(at 0 0 270)
			(layer "F.Fab")
			(effects
				(font
					(size 1.27 1.27)
				)
			)
		)
		(duplicate_pad_numbers_are_jumpers no)
		(fp_line
			(start -0.7874 0.4064)
			(end -0.7874 -0.4064)
			(stroke
				(width 0.1524)
				(type default)
			)
			(layer "F.SilkS")
		)
		(fp_line
			(start 0.7874 0.4064)
			(end -0.7874 0.4064)
			(stroke
				(width 0.1524)
				(type default)
			)
			(layer "F.SilkS")
		)
		(fp_line
			(start -0.7874 -0.4064)
			(end 0.7874 -0.4064)
			(stroke
				(width 0.1524)
				(type default)
			)
			(layer "F.SilkS")
		)
		(fp_line
			(start 0.7874 -0.4064)
			(end 0.7874 0.4064)
			(stroke
				(width 0.1524)
				(type default)
			)
			(layer "F.SilkS")
		)
		(fp_line
			(start -0.67945 0.3048)
			(end -0.67945 -0.305054)
			(stroke
				(width 0.1)
				(type default)
			)
			(layer "F.Fab")
		)
		(fp_line
			(start -0.12065 0.3048)
			(end -0.67945 0.3048)
			(stroke
				(width 0.1)
				(type default)
			)
			(layer "F.Fab")
		)
		(fp_line
			(start 0.120396 0.3048)
			(end 0.120396 0.2794)
			(stroke
				(width 0.1)
				(type default)
			)
			(layer "F.Fab")
		)
		(fp_line
			(start 0.67945 0.3048)
			(end 0.120396 0.3048)
			(stroke
				(width 0.1)
				(type default)
			)
			(layer "F.Fab")
		)
		(fp_line
			(start -0.12065 0.2794)
			(end -0.12065 0.3048)
			(stroke
				(width 0.1)
				(type default)
			)
			(layer "F.Fab")
		)
		(fp_line
			(start 0.120396 0.2794)
			(end -0.12065 0.2794)
			(stroke
				(width 0.1)
				(type default)
			)
			(layer "F.Fab")
		)
		(fp_line
			(start -0.12065 -0.2794)
			(end 0.12065 -0.2794)
			(stroke
				(width 0.1)
				(type default)
			)
			(layer "F.Fab")
		)
		(fp_line
			(start 0.12065 -0.2794)
			(end 0.12065 -0.3048)
			(stroke
				(width 0.1)
				(type default)
			)
			(layer "F.Fab")
		)
		(fp_line
			(start 0.12065 -0.3048)
			(end 0.67945 -0.3048)
			(stroke
				(width 0.1)
				(type default)
			)
			(layer "F.Fab")
		)
		(fp_line
			(start 0.67945 -0.3048)
			(end 0.67945 0.3048)
			(stroke
				(width 0.1)
				(type default)
			)
			(layer "F.Fab")
		)
		(fp_line
			(start -0.67945 -0.305054)
			(end -0.12065 -0.305054)
			(stroke
				(width 0.1)
				(type default)
			)
			(layer "F.Fab")
		)
		(fp_line
			(start -0.12065 -0.305054)
			(end -0.12065 -0.2794)
			(stroke
				(width 0.1)
				(type default)
			)
			(layer "F.Fab")
		)
		(pad "1" smd circle
			(at -0.40005 0 270)
			(size 0 0)
			(layers "F.Cu" "F.Mask" "F.Paste")
			(net "P12V_SCM_FAULT_N")
		)
		(pad "2" smd circle
			(at 0.40005 0 270)
			(size 0 0)
			(layers "F.Cu" "F.Mask" "F.Paste")
			(net "P12V_SCM_FAULT_R_N")
		)
	)
)
